FILE_TYPE = MACRO_DRAWING;
SET COLOR_WIRE YELLOW;
SET COLOR_PROP ORANGE;
SET COLOR_DOT WHITE;
SET COLOR_ARC YELLOW;
SET COLOR_BODY GREEN;
SET COLOR_NOTE PURPLE;
SET PROP_DISPLAY VALUE;
SET PAGE_NUMBER P35;
FORCEADD SOCKET4677_AZIF0045P001C01CS..25
(650 2600);
FORCEPROP 1 LAST PART_NUMBER DGA^7000023
J 0
(-400 4050);
DISPLAY 0.723404 (-400 4050);
PAINT GREEN (-400 4050);
DISPLAY INVISIBLE (-400 4050);
FORCEPROP 1 LAST MATERIAL IO
J 0
(-400 3975);
DISPLAY 0.723404 (-400 3975);
PAINT GREEN (-400 3975);
FORCEPROP 2 LAST PART_TYPE SMLF
J 0
(-400 4225);
DISPLAY 1.021277 (-400 4225);
FORCEPROP 2 LAST VALUE SOCKET4677_AZIF0045-P001C01CS
J 0
(-400 4175);
DISPLAY 1.021277 (-400 4175);
FORCEPROP 1 LAST $LOCATION U2
J 0
(-400 4125);
DISPLAY 0.723404 (-400 4125);
PAINT GREEN (-400 4125);
FORCEPROP 0 LASTPIN (-550 1400) $PN EJ80
J 2
(-560 1410);
DISPLAY 0.680851 (-560 1410);
PAINT MONO (-560 1410);
FORCEPROP 0 LASTPIN (-550 1450) $PN EP81
J 2
(-560 1460);
DISPLAY 0.680851 (-560 1460);
PAINT MONO (-560 1460);
FORCEPROP 0 LASTPIN (-550 1500) $PN EL82
J 2
(-560 1510);
DISPLAY 0.680851 (-560 1510);
PAINT MONO (-560 1510);
FORCEPROP 0 LASTPIN (-550 1550) $PN EK81
J 2
(-560 1560);
DISPLAY 0.680851 (-560 1560);
PAINT MONO (-560 1560);
FORCEPROP 0 LASTPIN (-550 1600) $PN EF81
J 2
(-560 1610);
DISPLAY 0.680851 (-560 1610);
PAINT MONO (-560 1610);
FORCEPROP 0 LASTPIN (-550 1650) $PN ED83
J 2
(-560 1660);
DISPLAY 0.680851 (-560 1660);
PAINT MONO (-560 1660);
FORCEPROP 0 LASTPIN (-550 1700) $PN EC80
J 2
(-560 1710);
DISPLAY 0.680851 (-560 1710);
PAINT MONO (-560 1710);
FORCEPROP 0 LASTPIN (-550 1750) $PN EA82
J 2
(-560 1760);
DISPLAY 0.680851 (-560 1760);
PAINT MONO (-560 1760);
FORCEPROP 0 LASTPIN (-550 1800) $PN DY81
J 2
(-560 1810);
DISPLAY 0.680851 (-560 1810);
PAINT MONO (-560 1810);
FORCEPROP 0 LASTPIN (-550 1850) $PN DJ78
J 2
(-560 1860);
DISPLAY 0.680851 (-560 1860);
PAINT MONO (-560 1860);
FORCEPROP 0 LASTPIN (-550 1900) $PN DG78
J 2
(-560 1910);
DISPLAY 0.680851 (-560 1910);
PAINT MONO (-560 1910);
FORCEPROP 0 LASTPIN (-550 1950) $PN DH81
J 2
(-560 1960);
DISPLAY 0.680851 (-560 1960);
PAINT MONO (-560 1960);
FORCEPROP 0 LASTPIN (-550 2000) $PN DF83
J 2
(-560 2010);
DISPLAY 0.680851 (-560 2010);
PAINT MONO (-560 2010);
FORCEPROP 0 LASTPIN (-550 2050) $PN DE80
J 2
(-560 2060);
DISPLAY 0.680851 (-560 2060);
PAINT MONO (-560 2060);
FORCEPROP 0 LASTPIN (-550 2100) $PN DC82
J 2
(-560 2110);
DISPLAY 0.680851 (-560 2110);
PAINT MONO (-560 2110);
FORCEPROP 0 LASTPIN (-550 2150) $PN DB81
J 2
(-560 2160);
DISPLAY 0.680851 (-560 2160);
PAINT MONO (-560 2160);
FORCEPROP 0 LASTPIN (-550 2200) $PN DF77
J 2
(-560 2210);
DISPLAY 0.680851 (-560 2210);
PAINT MONO (-560 2210);
FORCEPROP 0 LASTPIN (-550 2250) $PN CU82
J 2
(-560 2260);
DISPLAY 0.680851 (-560 2260);
PAINT MONO (-560 2260);
FORCEPROP 0 LASTPIN (-550 2300) $PN CR82
J 2
(-560 2310);
DISPLAY 0.680851 (-560 2310);
PAINT MONO (-560 2310);
FORCEPROP 0 LASTPIN (-550 2350) $PN CW80
J 2
(-560 2360);
DISPLAY 0.680851 (-560 2360);
PAINT MONO (-560 2360);
FORCEPROP 0 LASTPIN (-550 2400) $PN CP81
J 2
(-560 2410);
DISPLAY 0.680851 (-560 2410);
PAINT MONO (-560 2410);
FORCEPROP 0 LASTPIN (-550 2450) $PN CN80
J 2
(-560 2460);
DISPLAY 0.680851 (-560 2460);
PAINT MONO (-560 2460);
FORCEPROP 0 LASTPIN (-550 2500) $PN CT79
J 2
(-560 2510);
DISPLAY 0.680851 (-560 2510);
PAINT MONO (-560 2510);
FORCEPROP 0 LASTPIN (-550 2550) $PN DA78
J 2
(-560 2560);
DISPLAY 0.680851 (-560 2560);
PAINT MONO (-560 2560);
FORCEPROP 0 LASTPIN (-550 2650) $PN EL80
J 2
(-560 2660);
DISPLAY 0.680851 (-560 2660);
PAINT MONO (-560 2660);
FORCEPROP 0 LASTPIN (-550 2700) $PN ER82
J 2
(-560 2710);
DISPLAY 0.680851 (-560 2710);
PAINT MONO (-560 2710);
FORCEPROP 0 LASTPIN (-550 2750) $PN EN82
J 2
(-560 2760);
DISPLAY 0.680851 (-560 2760);
PAINT MONO (-560 2760);
FORCEPROP 0 LASTPIN (-550 2800) $PN EJ82
J 2
(-560 2810);
DISPLAY 0.680851 (-560 2810);
PAINT MONO (-560 2810);
FORCEPROP 0 LASTPIN (-550 2850) $PN EE82
J 2
(-560 2860);
DISPLAY 0.680851 (-560 2860);
PAINT MONO (-560 2860);
FORCEPROP 0 LASTPIN (-550 2900) $PN EF83
J 2
(-560 2910);
DISPLAY 0.680851 (-560 2910);
PAINT MONO (-560 2910);
FORCEPROP 0 LASTPIN (-550 2950) $PN ED81
J 2
(-560 2960);
DISPLAY 0.680851 (-560 2960);
PAINT MONO (-560 2960);
FORCEPROP 0 LASTPIN (-550 3000) $PN DY83
J 2
(-560 3010);
DISPLAY 0.680851 (-560 3010);
PAINT MONO (-560 3010);
FORCEPROP 0 LASTPIN (-550 3050) $PN EB81
J 2
(-560 3060);
DISPLAY 0.680851 (-560 3060);
PAINT MONO (-560 3060);
FORCEPROP 0 LASTPIN (-550 3100) $PN DL78
J 2
(-560 3110);
DISPLAY 0.680851 (-560 3110);
PAINT MONO (-560 3110);
FORCEPROP 0 LASTPIN (-550 3150) $PN DH79
J 2
(-560 3160);
DISPLAY 0.680851 (-560 3160);
PAINT MONO (-560 3160);
FORCEPROP 0 LASTPIN (-550 3200) $PN DG82
J 2
(-560 3210);
DISPLAY 0.680851 (-560 3210);
PAINT MONO (-560 3210);
FORCEPROP 0 LASTPIN (-550 3250) $PN DH83
J 2
(-560 3260);
DISPLAY 0.680851 (-560 3260);
PAINT MONO (-560 3260);
FORCEPROP 0 LASTPIN (-550 3300) $PN DF81
J 2
(-560 3310);
DISPLAY 0.680851 (-560 3310);
PAINT MONO (-560 3310);
FORCEPROP 0 LASTPIN (-550 3350) $PN DB83
J 2
(-560 3360);
DISPLAY 0.680851 (-560 3360);
PAINT MONO (-560 3360);
FORCEPROP 0 LASTPIN (-550 3400) $PN DD81
J 2
(-560 3410);
DISPLAY 0.680851 (-560 3410);
PAINT MONO (-560 3410);
FORCEPROP 0 LASTPIN (-550 3450) $PN DE78
J 2
(-560 3460);
DISPLAY 0.680851 (-560 3460);
PAINT MONO (-560 3460);
FORCEPROP 0 LASTPIN (-550 3500) $PN CW82
J 2
(-560 3510);
DISPLAY 0.680851 (-560 3510);
PAINT MONO (-560 3510);
FORCEPROP 0 LASTPIN (-550 3550) $PN CT83
J 2
(-560 3560);
DISPLAY 0.680851 (-560 3560);
PAINT MONO (-560 3560);
FORCEPROP 0 LASTPIN (-550 3600) $PN CV81
J 2
(-560 3610);
DISPLAY 0.680851 (-560 3610);
PAINT MONO (-560 3610);
FORCEPROP 0 LASTPIN (-550 3650) $PN CN82
J 2
(-560 3660);
DISPLAY 0.680851 (-560 3660);
PAINT MONO (-560 3660);
FORCEPROP 0 LASTPIN (-550 3700) $PN CR80
J 2
(-560 3710);
DISPLAY 0.680851 (-560 3710);
PAINT MONO (-560 3710);
FORCEPROP 0 LASTPIN (-550 3750) $PN CU80
J 2
(-560 3760);
DISPLAY 0.680851 (-560 3760);
PAINT MONO (-560 3760);
FORCEPROP 0 LASTPIN (-550 3800) $PN DB79
J 2
(-560 3810);
DISPLAY 0.680851 (-560 3810);
PAINT MONO (-560 3810);
FORCEPROP 0 LASTPIN (1850 1400) $PN EH85
J 0
(1860 1410);
DISPLAY 0.680851 (1860 1410);
PAINT MONO (1860 1410);
FORCEPROP 0 LASTPIN (1850 1450) $PN EL84
J 0
(1860 1460);
DISPLAY 0.680851 (1860 1460);
PAINT MONO (1860 1460);
FORCEPROP 0 LASTPIN (1850 1500) $PN EP85
J 0
(1860 1510);
DISPLAY 0.680851 (1860 1510);
PAINT MONO (1860 1510);
FORCEPROP 0 LASTPIN (1850 1550) $PN EM87
J 0
(1860 1560);
DISPLAY 0.680851 (1860 1560);
PAINT MONO (1860 1560);
FORCEPROP 0 LASTPIN (1850 1600) $PN EJ86
J 0
(1860 1610);
DISPLAY 0.680851 (1860 1610);
PAINT MONO (1860 1610);
FORCEPROP 0 LASTPIN (1850 1650) $PN EK87
J 0
(1860 1660);
DISPLAY 0.680851 (1860 1660);
PAINT MONO (1860 1660);
FORCEPROP 0 LASTPIN (1850 1700) $PN DU80
J 0
(1860 1710);
DISPLAY 0.680851 (1860 1710);
PAINT MONO (1860 1710);
FORCEPROP 0 LASTPIN (1850 1750) $PN DR82
J 0
(1860 1760);
DISPLAY 0.680851 (1860 1760);
PAINT MONO (1860 1760);
FORCEPROP 0 LASTPIN (1850 1800) $PN DP79
J 0
(1860 1810);
DISPLAY 0.680851 (1860 1810);
PAINT MONO (1860 1810);
FORCEPROP 0 LASTPIN (1850 1850) $PN DN82
J 0
(1860 1860);
DISPLAY 0.680851 (1860 1860);
PAINT MONO (1860 1860);
FORCEPROP 0 LASTPIN (1850 1900) $PN DM81
J 0
(1860 1910);
DISPLAY 0.680851 (1860 1910);
PAINT MONO (1860 1910);
FORCEPROP 0 LASTPIN (1850 1950) $PN DL80
J 0
(1860 1960);
DISPLAY 0.680851 (1860 1960);
PAINT MONO (1860 1960);
FORCEPROP 0 LASTPIN (1850 2000) $PN CW76
J 0
(1860 2010);
DISPLAY 0.680851 (1860 2010);
PAINT MONO (1860 2010);
FORCEPROP 0 LASTPIN (1850 2050) $PN CU76
J 0
(1860 2060);
DISPLAY 0.680851 (1860 2060);
PAINT MONO (1860 2060);
FORCEPROP 0 LASTPIN (1850 2100) $PN CT75
J 0
(1860 2110);
DISPLAY 0.680851 (1860 2110);
PAINT MONO (1860 2110);
FORCEPROP 0 LASTPIN (1850 2150) $PN CR74
J 0
(1860 2160);
DISPLAY 0.680851 (1860 2160);
PAINT MONO (1860 2160);
FORCEPROP 0 LASTPIN (1850 2200) $PN CK77
J 0
(1860 2210);
DISPLAY 0.680851 (1860 2210);
PAINT MONO (1860 2210);
FORCEPROP 0 LASTPIN (1850 2250) $PN CH77
J 0
(1860 2260);
DISPLAY 0.680851 (1860 2260);
PAINT MONO (1860 2260);
FORCEPROP 0 LASTPIN (1850 2300) $PN CM75
J 0
(1860 2310);
DISPLAY 0.680851 (1860 2310);
PAINT MONO (1860 2310);
FORCEPROP 0 LASTPIN (1850 2350) $PN CG76
J 0
(1860 2360);
DISPLAY 0.680851 (1860 2360);
PAINT MONO (1860 2360);
FORCEPROP 0 LASTPIN (1850 2400) $PN CF75
J 0
(1860 2410);
DISPLAY 0.680851 (1860 2410);
PAINT MONO (1860 2410);
FORCEPROP 0 LASTPIN (1850 2450) $PN CJ74
J 0
(1860 2460);
DISPLAY 0.680851 (1860 2460);
PAINT MONO (1860 2460);
FORCEPROP 0 LASTPIN (1850 2500) $PN CV73
J 0
(1860 2510);
DISPLAY 0.680851 (1860 2510);
PAINT MONO (1860 2510);
FORCEPROP 0 LASTPIN (1850 2550) $PN CF73
J 0
(1860 2560);
DISPLAY 0.680851 (1860 2560);
PAINT MONO (1860 2560);
FORCEPROP 0 LASTPIN (1850 2650) $PN EK85
J 0
(1860 2660);
DISPLAY 0.680851 (1860 2660);
PAINT MONO (1860 2660);
FORCEPROP 0 LASTPIN (1850 2700) $PN EM85
J 0
(1860 2710);
DISPLAY 0.680851 (1860 2710);
PAINT MONO (1860 2710);
FORCEPROP 0 LASTPIN (1850 2750) $PN EN86
J 0
(1860 2760);
DISPLAY 0.680851 (1860 2760);
PAINT MONO (1860 2760);
FORCEPROP 0 LASTPIN (1850 2800) $PN EP87
J 0
(1860 2810);
DISPLAY 0.680851 (1860 2810);
PAINT MONO (1860 2810);
FORCEPROP 0 LASTPIN (1850 2850) $PN EH87
J 0
(1860 2860);
DISPLAY 0.680851 (1860 2860);
PAINT MONO (1860 2860);
FORCEPROP 0 LASTPIN (1850 2900) $PN EL88
J 0
(1860 2910);
DISPLAY 0.680851 (1860 2910);
PAINT MONO (1860 2910);
FORCEPROP 0 LASTPIN (1850 2950) $PN DT81
J 0
(1860 2960);
DISPLAY 0.680851 (1860 2960);
PAINT MONO (1860 2960);
FORCEPROP 0 LASTPIN (1850 3000) $PN DU82
J 0
(1860 3010);
DISPLAY 0.680851 (1860 3010);
PAINT MONO (1860 3010);
FORCEPROP 0 LASTPIN (1850 3050) $PN DR80
J 0
(1860 3060);
DISPLAY 0.680851 (1860 3060);
PAINT MONO (1860 3060);
FORCEPROP 0 LASTPIN (1850 3100) $PN DP83
J 0
(1860 3110);
DISPLAY 0.680851 (1860 3110);
PAINT MONO (1860 3110);
FORCEPROP 0 LASTPIN (1850 3150) $PN DL82
J 0
(1860 3160);
DISPLAY 0.680851 (1860 3160);
PAINT MONO (1860 3160);
FORCEPROP 0 LASTPIN (1850 3200) $PN DN80
J 0
(1860 3210);
DISPLAY 0.680851 (1860 3210);
PAINT MONO (1860 3210);
FORCEPROP 0 LASTPIN (1850 3250) $PN DA76
J 0
(1860 3260);
DISPLAY 0.680851 (1860 3260);
PAINT MONO (1860 3260);
FORCEPROP 0 LASTPIN (1850 3300) $PN CV77
J 0
(1860 3310);
DISPLAY 0.680851 (1860 3310);
PAINT MONO (1860 3310);
FORCEPROP 0 LASTPIN (1850 3350) $PN CR76
J 0
(1860 3360);
DISPLAY 0.680851 (1860 3360);
PAINT MONO (1860 3360);
FORCEPROP 0 LASTPIN (1850 3400) $PN CU74
J 0
(1860 3410);
DISPLAY 0.680851 (1860 3410);
PAINT MONO (1860 3410);
FORCEPROP 0 LASTPIN (1850 3450) $PN CM77
J 0
(1860 3460);
DISPLAY 0.680851 (1860 3460);
PAINT MONO (1860 3460);
FORCEPROP 0 LASTPIN (1850 3500) $PN CJ78
J 0
(1860 3510);
DISPLAY 0.680851 (1860 3510);
PAINT MONO (1860 3510);
FORCEPROP 0 LASTPIN (1850 3550) $PN CL76
J 0
(1860 3560);
DISPLAY 0.680851 (1860 3560);
PAINT MONO (1860 3560);
FORCEPROP 0 LASTPIN (1850 3600) $PN CF77
J 0
(1860 3610);
DISPLAY 0.680851 (1860 3610);
PAINT MONO (1860 3610);
FORCEPROP 0 LASTPIN (1850 3650) $PN CH75
J 0
(1860 3660);
DISPLAY 0.680851 (1860 3660);
PAINT MONO (1860 3660);
FORCEPROP 0 LASTPIN (1850 3700) $PN CK75
J 0
(1860 3710);
DISPLAY 0.680851 (1860 3710);
PAINT MONO (1860 3710);
FORCEPROP 0 LASTPIN (1850 3750) $PN CW74
J 0
(1860 3760);
DISPLAY 0.680851 (1860 3760);
PAINT MONO (1860 3760);
FORCEPROP 0 LASTPIN (1850 3800) $PN CD73
J 0
(1860 3810);
DISPLAY 0.680851 (1860 3810);
PAINT MONO (1860 3810);
FORCEPROP 1 LAST CDS_LMAN_SYM_OUTLINE -1050,1350,1050,-1350
J 0
(650 2600);
DISPLAY 0.468085 (650 2600);
PAINT GREEN (650 2600);
DISPLAY INVISIBLE (650 2600);
FORCEPROP 1 LAST NEEDS_NO_SIZE TRUE
J 0
(650 2600);
DISPLAY 0.723404 (650 2600);
PAINT GREEN (650 2600);
DISPLAY INVISIBLE (650 2600);
FORCEPROP 2 LAST CDS_LIB pure_quanta
J 0
(650 2600);
DISPLAY INVISIBLE (650 2600);
FORCEPROP 2 LAST CDS_LOCATION U2
J 0
(-400 4275);
DISPLAY 1.021277 (-400 4275);
DISPLAY INVISIBLE (-400 4275);
FORCEPROP 0 LAST $SEC 25
J 0
(-400 4275);
DISPLAY 0.680851 (-400 4275);
PAINT MONO (-400 4275);
DISPLAY INVISIBLE (-400 4275);
FORCEPROP 2 LAST CDS_SEC 25
J 0
(-400 4275);
DISPLAY 1.021277 (-400 4275);
DISPLAY INVISIBLE (-400 4275);
FORCEPROP 1 LAST PATH I102
J 0
(650 2600);
DISPLAY 0.723404 (650 2600);
PAINT GREEN (650 2600);
DISPLAY INVISIBLE (650 2600);
FORCEADD UNIVERSAL_GND..1
(-850 1075);
FORCEPROP 3 LASTPIN (-850 1125) SIG_NAME GND\g
J 0
(-840 1135);
DISPLAY 0.659574 (-840 1135);
PAINT MONO (-840 1135);
DISPLAY INVISIBLE (-840 1135);
FORCEPROP 2 LAST CDS_LIB logical_power
J 0
(-850 1075);
DISPLAY INVISIBLE (-850 1075);
FORCEPROP 1 LAST HDL_POWER GND
J 1
(-825 1000);
DISPLAY 0.872340 (-825 1000);
PAINT GREEN (-825 1000);
DISPLAY INVISIBLE (-825 1000);
FORCEPROP 1 LAST PATH I104
J 0
(-775 1075);
DISPLAY 0.872340 (-775 1075);
PAINT AQUA (-775 1075);
DISPLAY INVISIBLE (-775 1075);
FORCEADD QUANTA_TITLE_BLOCK_C..1
(5250 -1700);
FORCEPROP 0 LAST CDS_CON_LAST_MODIFIED Fri Aug 25 14:00:19 2023
J 0
(3365 -1685);
PAINT MONO (3365 -1685);
DISPLAY INVISIBLE (3365 -1685);
FORCEPROP 1 LAST CUSTOM_TXT_CDS <CON_LAST_MODIFIED>
J 0
(3365 -1685);
DISPLAY 0.978723 (3365 -1685);
FORCEPROP 2 LAST CUSTOM_TXT_CDS <XR_PAGE_TITLE>
J 0
(-2640 3550);
DISPLAY 0.638298 (-2640 3550);
PAINT PINK (-2640 3550);
DISPLAY INVISIBLE (-2640 3550);
FORCEPROP 2 LAST CUSTOM_TXT_CDS <Q_NUMBER>
J 0
(3847 -1597);
DISPLAY 1.212766 (3847 -1597);
FORCEPROP 1 LAST CUSTOM_TXT_CDS <NAME_2>
J 0
(2075 -1650);
FORCEPROP 1 LAST CUSTOM_TXT_CDS <NAME_1>
J 0
(2075 -1525);
FORCEPROP 1 LAST CUSTOM_TXT_CDS <Q_PROJ>
J 0
(2868 -1598);
DISPLAY 1.212766 (2868 -1598);
FORCEPROP 1 LAST CUSTOM_TXT_CDS <Q_REV>
J 0
(5066 -1597);
DISPLAY 1.212766 (5066 -1597);
FORCEPROP 1 LAST CUSTOM_TXT_CDS <CON_PAGE_NUM> OF <CON_TOTAL_PAGES>
J 0
(4804 -1682);
DISPLAY 0.978723 (4804 -1682);
FORCEPROP 1 LAST Q_TITLE SPR CPU0 - UPI3 (23 OF 30)
J 0
(-4116 -1674);
DISPLAY 1.957447 (-4116 -1674);
PAINT GREEN (-4116 -1674);
FORCEPROP 1 LAST Q_DEPT 
J 1
(1487 -1651);
DISPLAY 1.957447 (1487 -1651);
PAINT GREEN (1487 -1651);
FORCEPROP 2 LAST CDS_LIB pure_quanta
J 0
(5250 -1700);
PAINT MONO (5250 -1700);
DISPLAY INVISIBLE (5250 -1700);
FORCEPROP 1 LAST CDS_LMAN_SYM_OUTLINE -9475,6775,100,-125
J 0
(5250 -1700);
DISPLAY 0.468085 (5250 -1700);
PAINT GREEN (5250 -1700);
DISPLAY INVISIBLE (5250 -1700);
FORCEPROP 2 LAST PAGE_BORDER TRUE
J 0
(-2640 3550);
DISPLAY 0.638298 (-2640 3550);
PAINT PINK (-2640 3550);
DISPLAY INVISIBLE (-2640 3550);
FORCEPROP 2 LAST CDS_XR_PAGE_TITLE CR-35 : @S9S_MB_2U_LIB.S9S_MB_2U(SCH_1):PAGE35
J 0
(-2640 3550);
DISPLAY 0.638298 (-2640 3550);
PAINT PINK (-2640 3550);
DISPLAY INVISIBLE (-2640 3550);
FORCEPROP 1 LAST COMMENT_BODY TRUE
J 0
(5262 -1713);
DISPLAY 0.978723 (5262 -1713);
PAINT GREEN (5262 -1713);
DISPLAY INVISIBLE (5262 -1713);
WIRE 16 -1 (-850 1400)(-850 1125);
WIRE 16 -1 (-850 1450)(-850 1400);
WIRE 16 -1 (-850 1400)(-550 1400);
WIRE 16 -1 (-850 3800)(-550 3800);
WIRE 16 -1 (-850 3800)(-850 3750);
WIRE 16 -1 (-850 3750)(-550 3750);
WIRE 16 -1 (-850 3750)(-850 3700);
WIRE 16 -1 (-850 3700)(-550 3700);
WIRE 16 -1 (-850 3700)(-850 3650);
WIRE 16 -1 (-850 3650)(-550 3650);
WIRE 16 -1 (-850 3650)(-850 3600);
WIRE 16 -1 (-850 3600)(-550 3600);
WIRE 16 -1 (-850 3550)(-550 3550);
WIRE 16 -1 (-850 3600)(-850 3550);
WIRE 16 -1 (-850 3550)(-850 3500);
WIRE 16 -1 (-850 3500)(-550 3500);
WIRE 16 -1 (-850 3500)(-850 3450);
WIRE 16 -1 (-850 3450)(-550 3450);
WIRE 16 -1 (-850 3450)(-850 3400);
WIRE 16 -1 (-850 3400)(-550 3400);
WIRE 16 -1 (-850 3400)(-850 3350);
WIRE 16 -1 (-850 3350)(-550 3350);
WIRE 16 -1 (-850 3350)(-850 3300);
WIRE 16 -1 (-850 3300)(-550 3300);
WIRE 16 -1 (-850 3300)(-850 3250);
WIRE 16 -1 (-850 3250)(-550 3250);
WIRE 16 -1 (-850 3250)(-850 3200);
WIRE 16 -1 (-850 3200)(-550 3200);
WIRE 16 -1 (-850 3200)(-850 3150);
WIRE 16 -1 (-850 3150)(-550 3150);
WIRE 16 -1 (-850 3150)(-850 3100);
WIRE 16 -1 (-850 3100)(-550 3100);
WIRE 16 -1 (-850 3050)(-550 3050);
WIRE 16 -1 (-850 3100)(-850 3050);
WIRE 16 -1 (-850 3050)(-850 3000);
WIRE 16 -1 (-850 3000)(-550 3000);
WIRE 16 -1 (-850 3000)(-850 2950);
WIRE 16 -1 (-850 2950)(-550 2950);
WIRE 16 -1 (-850 2950)(-850 2900);
WIRE 16 -1 (-850 2900)(-550 2900);
WIRE 16 -1 (-850 2900)(-850 2850);
WIRE 16 -1 (-850 2850)(-550 2850);
WIRE 16 -1 (-850 2850)(-850 2800);
WIRE 16 -1 (-850 2800)(-550 2800);
WIRE 16 -1 (-850 2800)(-850 2750);
WIRE 16 -1 (-850 2750)(-550 2750);
WIRE 16 -1 (-850 2750)(-850 2700);
WIRE 16 -1 (-850 2700)(-550 2700);
WIRE 16 -1 (-850 2700)(-850 2650);
WIRE 16 -1 (-850 2650)(-550 2650);
WIRE 16 -1 (-850 2550)(-550 2550);
WIRE 16 -1 (-850 2650)(-850 2550);
WIRE 16 -1 (-850 2550)(-850 2500);
WIRE 16 -1 (-850 2500)(-550 2500);
WIRE 16 -1 (-850 2500)(-850 2450);
WIRE 16 -1 (-850 2450)(-550 2450);
WIRE 16 -1 (-850 2450)(-850 2400);
WIRE 16 -1 (-850 2400)(-550 2400);
WIRE 16 -1 (-850 2400)(-850 2350);
WIRE 16 -1 (-850 2350)(-550 2350);
WIRE 16 -1 (-850 2350)(-850 2300);
WIRE 16 -1 (-850 2300)(-550 2300);
WIRE 16 -1 (-850 2300)(-850 2250);
WIRE 16 -1 (-850 2250)(-550 2250);
WIRE 16 -1 (-850 2250)(-850 2200);
WIRE 16 -1 (-850 2200)(-550 2200);
WIRE 16 -1 (-850 2200)(-850 2150);
WIRE 16 -1 (-850 2150)(-550 2150);
WIRE 16 -1 (-850 2150)(-850 2100);
WIRE 16 -1 (-850 2100)(-550 2100);
WIRE 16 -1 (-850 2100)(-850 2050);
WIRE 16 -1 (-850 2050)(-550 2050);
WIRE 16 -1 (-850 2000)(-550 2000);
WIRE 16 -1 (-850 2050)(-850 2000);
WIRE 16 -1 (-850 2000)(-850 1950);
WIRE 16 -1 (-850 1950)(-550 1950);
WIRE 16 -1 (-850 1950)(-850 1900);
WIRE 16 -1 (-850 1900)(-550 1900);
WIRE 16 -1 (-850 1900)(-850 1850);
WIRE 16 -1 (-850 1850)(-550 1850);
WIRE 16 -1 (-850 1850)(-850 1800);
WIRE 16 -1 (-850 1800)(-550 1800);
WIRE 16 -1 (-850 1800)(-850 1750);
WIRE 16 -1 (-850 1750)(-550 1750);
WIRE 16 -1 (-850 1750)(-850 1700);
WIRE 16 -1 (-850 1700)(-550 1700);
WIRE 16 -1 (-850 1700)(-850 1650);
WIRE 16 -1 (-850 1650)(-550 1650);
WIRE 16 -1 (-850 1650)(-850 1600);
WIRE 16 -1 (-850 1600)(-550 1600);
WIRE 16 -1 (-850 1600)(-850 1550);
WIRE 16 -1 (-850 1550)(-550 1550);
WIRE 16 -1 (-850 1500)(-550 1500);
WIRE 16 -1 (-850 1550)(-850 1500);
WIRE 16 -1 (-850 1500)(-850 1450);
WIRE 16 -1 (-850 1450)(-550 1450);
WIRE 16 2175 (1275 1100)(2100 1100);
WIRE 16 2175 (2100 4075)(2100 1100);
WIRE 16 2175 (1275 4075)(1275 1100);
WIRE 16 2175 (1275 4075)(2100 4075);
DOT 1 (-850 3750);
DOT 1 (-850 3700);
DOT 1 (-850 3650);
DOT 1 (-850 3600);
DOT 1 (-850 3550);
DOT 1 (-850 3500);
DOT 1 (-850 3450);
DOT 1 (-850 3400);
DOT 1 (-850 3350);
DOT 1 (-850 3300);
DOT 1 (-850 3250);
DOT 1 (-850 3200);
DOT 1 (-850 3150);
DOT 1 (-850 3100);
DOT 1 (-850 3050);
DOT 1 (-850 3000);
DOT 1 (-850 2950);
DOT 1 (-850 2900);
DOT 1 (-850 2850);
DOT 1 (-850 2800);
DOT 1 (-850 2750);
DOT 1 (-850 2700);
DOT 1 (-850 2650);
DOT 1 (-850 2550);
DOT 1 (-850 2500);
DOT 1 (-850 2450);
DOT 1 (-850 2400);
DOT 1 (-850 2350);
DOT 1 (-850 2300);
DOT 1 (-850 2250);
DOT 1 (-850 2200);
DOT 1 (-850 2150);
DOT 1 (-850 2100);
DOT 1 (-850 2050);
DOT 1 (-850 2000);
DOT 1 (-850 1950);
DOT 1 (-850 1900);
DOT 1 (-850 1850);
DOT 1 (-850 1800);
DOT 1 (-850 1750);
DOT 1 (-850 1700);
DOT 1 (-850 1650);
DOT 1 (-850 1600);
DOT 1 (-850 1550);
DOT 1 (-850 1500);
DOT 1 (-850 1450);
DOT 1 (-850 1400);
FORCENOTE
20211129 CHANGE TX FLOATING
(325 750) 0;
DISPLAY LEFT (325 750);
DISPLAY 2.510638 (325 750);
PAINT PINK (325 750);
FORCENOTE
20211122 MODIFY FOR GT
(-3875 4675) 0;
DISPLAY LEFT (-3875 4675);
DISPLAY 2.510638 (-3875 4675);
PAINT PINK (-3875 4675);
QUIT
